(kicad_pcb
	(version 20260206)
	(generator "pcbnew")
	(generator_version "10.0")
	(general
		(thickness 1.6)
		(legacy_teardrops no)
	)
	(paper "A4")
	(title_block
		(title "01162023_DA0F0TEBIF0_F0T_Expander_BD_F_brd_V02_OCP.brd")
		(comment 1 "Grand Teton / footprints 2877-2886 of 9728")
	)
	(layers
		(0 "F.Cu" signal "TOP")
		(4 "In1.Cu" signal "GND")
		(6 "In2.Cu" signal "VCC")
		(8 "In3.Cu" signal "VCC1")
		(10 "In4.Cu" signal "GND1")
		(12 "In5.Cu" signal "IN1")
		(14 "In6.Cu" signal "GND2")
		(16 "In7.Cu" signal "IN2")
		(18 "In8.Cu" signal "GND3")
		(20 "In9.Cu" signal "IN3")
		(22 "In10.Cu" signal "GND4")
		(24 "In11.Cu" signal "IN4")
		(26 "In12.Cu" signal "GND5")
		(28 "In13.Cu" signal "IN5")
		(30 "In14.Cu" signal "GND6")
		(32 "In15.Cu" signal "IN6")
		(34 "In16.Cu" signal "GND7")
		(2 "B.Cu" signal "BOTTOM")
		(9 "F.Adhes" user "F.Adhesive")
		(11 "B.Adhes" user "B.Adhesive")
		(13 "F.Paste" user "Package Geometry/Pastemask Top")
		(15 "B.Paste" user "Package Geometry/Pastemask Bottom")
		(5 "F.SilkS" user "Ref Des/Silkscreen Top")
		(7 "B.SilkS" user "Ref Des/Silkscreen Bottom")
		(1 "F.Mask" user "Board Geometry/Soldermask Top")
		(3 "B.Mask" user "Board Geometry/Soldermask Bottom")
		(17 "Dwgs.User" user "User.Drawings")
		(19 "Cmts.User" user "User.Comments")
		(21 "Eco1.User" user "User.Eco1")
		(23 "Eco2.User" user "User.Eco2")
		(25 "Edge.Cuts" user "Board Geometry/Outline")
		(27 "Margin" user)
		(31 "F.CrtYd" user "Package Geometry/Place Bound Top")
		(29 "B.CrtYd" user "Package Geometry/Place Bound Bottom")
		(35 "F.Fab" user "Ref Des/Assembly Top")
		(33 "B.Fab" user "Ref Des/Assembly Bottom")
	)
	(footprint ""
		(layer "F.Cu")
		(at 387.580632 -99.288854)
		(property "Reference" "C696"
			(at 0 0 0)
			(layer "F.SilkS")
			(hide yes)
			(effects
				(font
					(size 1.27 1.27)
				)
			)
		)
		(property "Value" ""
			(at 0 0 0)
			(layer "F.Fab")
			(effects
				(font
					(size 1.27 1.27)
				)
			)
		)
		(duplicate_pad_numbers_are_jumpers no)
		(fp_line
			(start -0.299974 -0.150114)
			(end 0.299974 -0.150114)
			(stroke
				(width 0.1)
				(type default)
			)
			(layer "F.Fab")
		)
		(fp_line
			(start -0.299974 0.150114)
			(end -0.299974 -0.150114)
			(stroke
				(width 0.1)
				(type default)
			)
			(layer "F.Fab")
		)
		(fp_line
			(start 0.299974 -0.150114)
			(end 0.299974 0.150114)
			(stroke
				(width 0.1)
				(type default)
			)
			(layer "F.Fab")
		)
		(fp_line
			(start 0.299974 0.150114)
			(end -0.299974 0.150114)
			(stroke
				(width 0.1)
				(type default)
			)
			(layer "F.Fab")
		)
		(pad "1" smd rect
			(at -0.2667 0)
			(size 0.3048 0.381)
			(layers "F.Cu" "F.Mask" "F.Paste")
			(net "P5E_PEX3_STN1_TX_DP<16>")
		)
		(pad "2" smd rect
			(at 0.2667 0)
			(size 0.3048 0.381)
			(layers "F.Cu" "F.Mask" "F.Paste")
			(net "P5E_PEX3_STN1_TX_C_DP<16>")
		)
	)
	(footprint ""
		(layer "F.Cu")
		(at 394.734542 -33.631886 180)
		(property "Reference" "C707"
			(at 0 0 180)
			(layer "F.SilkS")
			(hide yes)
			(effects
				(font
					(size 1.27 1.27)
				)
			)
		)
		(property "Value" ""
			(at 0 0 180)
			(layer "F.Fab")
			(effects
				(font
					(size 1.27 1.27)
				)
			)
		)
		(duplicate_pad_numbers_are_jumpers no)
		(fp_line
			(start 0.299974 0.150114)
			(end -0.299974 0.150114)
			(stroke
				(width 0.1)
				(type default)
			)
			(layer "F.Fab")
		)
		(fp_line
			(start 0.299974 -0.150114)
			(end 0.299974 0.150114)
			(stroke
				(width 0.1)
				(type default)
			)
			(layer "F.Fab")
		)
		(fp_line
			(start -0.299974 0.150114)
			(end -0.299974 -0.150114)
			(stroke
				(width 0.1)
				(type default)
			)
			(layer "F.Fab")
		)
		(fp_line
			(start -0.299974 -0.150114)
			(end 0.299974 -0.150114)
			(stroke
				(width 0.1)
				(type default)
			)
			(layer "F.Fab")
		)
		(pad "1" smd rect
			(at -0.2667 0 180)
			(size 0.3048 0.381)
			(layers "F.Cu" "F.Mask" "F.Paste")
			(net "P5E_PEX3_STN2_TX_DN<43>")
		)
		(pad "2" smd rect
			(at 0.2667 0 180)
			(size 0.3048 0.381)
			(layers "F.Cu" "F.Mask" "F.Paste")
			(net "P5E_PEX3_STN2_TX_C_DN<43>")
		)
	)
	(footprint ""
		(layer "F.Cu")
		(at 241.082322 -215.04529 180)
		(property "Reference" "R477"
			(at 0 0 180)
			(layer "F.SilkS")
			(hide yes)
			(effects
				(font
					(size 1.27 1.27)
				)
			)
		)
		(property "Value" ""
			(at 0 0 180)
			(layer "F.Fab")
			(effects
				(font
					(size 1.27 1.27)
				)
			)
		)
		(duplicate_pad_numbers_are_jumpers no)
		(fp_line
			(start 0.7874 0.4064)
			(end -0.7874 0.4064)
			(stroke
				(width 0.1524)
				(type default)
			)
			(layer "F.SilkS")
		)
		(fp_line
			(start 0.7874 -0.4064)
			(end 0.7874 0.4064)
			(stroke
				(width 0.1524)
				(type default)
			)
			(layer "F.SilkS")
		)
		(fp_line
			(start -0.7874 0.4064)
			(end -0.7874 -0.4064)
			(stroke
				(width 0.1524)
				(type default)
			)
			(layer "F.SilkS")
		)
		(fp_line
			(start -0.7874 -0.4064)
			(end 0.7874 -0.4064)
			(stroke
				(width 0.1524)
				(type default)
			)
			(layer "F.SilkS")
		)
		(fp_line
			(start 0.67945 0.3048)
			(end 0.120396 0.3048)
			(stroke
				(width 0.1)
				(type default)
			)
			(layer "F.Fab")
		)
		(fp_line
			(start 0.67945 -0.3048)
			(end 0.67945 0.3048)
			(stroke
				(width 0.1)
				(type default)
			)
			(layer "F.Fab")
		)
		(fp_line
			(start 0.12065 -0.2794)
			(end 0.12065 -0.3048)
			(stroke
				(width 0.1)
				(type default)
			)
			(layer "F.Fab")
		)
		(fp_line
			(start 0.12065 -0.3048)
			(end 0.67945 -0.3048)
			(stroke
				(width 0.1)
				(type default)
			)
			(layer "F.Fab")
		)
		(fp_line
			(start 0.120396 0.3048)
			(end 0.120396 0.2794)
			(stroke
				(width 0.1)
				(type default)
			)
			(layer "F.Fab")
		)
		(fp_line
			(start 0.120396 0.2794)
			(end -0.12065 0.2794)
			(stroke
				(width 0.1)
				(type default)
			)
			(layer "F.Fab")
		)
		(fp_line
			(start -0.12065 0.3048)
			(end -0.67945 0.3048)
			(stroke
				(width 0.1)
				(type default)
			)
			(layer "F.Fab")
		)
		(fp_line
			(start -0.12065 0.2794)
			(end -0.12065 0.3048)
			(stroke
				(width 0.1)
				(type default)
			)
			(layer "F.Fab")
		)
		(fp_line
			(start -0.12065 -0.2794)
			(end 0.12065 -0.2794)
			(stroke
				(width 0.1)
				(type default)
			)
			(layer "F.Fab")
		)
		(fp_line
			(start -0.12065 -0.305054)
			(end -0.12065 -0.2794)
			(stroke
				(width 0.1)
				(type default)
			)
			(layer "F.Fab")
		)
		(fp_line
			(start -0.67945 0.3048)
			(end -0.67945 -0.305054)
			(stroke
				(width 0.1)
				(type default)
			)
			(layer "F.Fab")
		)
		(fp_line
			(start -0.67945 -0.305054)
			(end -0.12065 -0.305054)
			(stroke
				(width 0.1)
				(type default)
			)
			(layer "F.Fab")
		)
		(pad "1" smd circle
			(at -0.40005 0 180)
			(size 0 0)
			(layers "F.Cu" "F.Mask" "F.Paste")
			(net "P3V3_AUX_SCALED")
		)
		(pad "2" smd circle
			(at 0.40005 0 180)
			(size 0 0)
			(layers "F.Cu" "F.Mask" "F.Paste")
			(net "GND")
		)
	)
	(footprint ""
		(layer "F.Cu")
		(at 405.594058 -34.248852)
		(property "Reference" "R5707"
			(at 0 0 0)
			(layer "F.SilkS")
			(hide yes)
			(effects
				(font
					(size 1.27 1.27)
				)
			)
		)
		(property "Value" ""
			(at 0 0 0)
			(layer "F.Fab")
			(effects
				(font
					(size 1.27 1.27)
				)
			)
		)
		(duplicate_pad_numbers_are_jumpers no)
		(fp_line
			(start -0.7874 -0.4064)
			(end 0.7874 -0.4064)
			(stroke
				(width 0.1524)
				(type default)
			)
			(layer "F.SilkS")
		)
		(fp_line
			(start -0.7874 0.4064)
			(end -0.7874 -0.4064)
			(stroke
				(width 0.1524)
				(type default)
			)
			(layer "F.SilkS")
		)
		(fp_line
			(start 0.7874 -0.4064)
			(end 0.7874 0.4064)
			(stroke
				(width 0.1524)
				(type default)
			)
			(layer "F.SilkS")
		)
		(fp_line
			(start 0.7874 0.4064)
			(end -0.7874 0.4064)
			(stroke
				(width 0.1524)
				(type default)
			)
			(layer "F.SilkS")
		)
		(fp_line
			(start -0.67945 -0.305054)
			(end -0.12065 -0.305054)
			(stroke
				(width 0.1)
				(type default)
			)
			(layer "F.Fab")
		)
		(fp_line
			(start -0.67945 0.3048)
			(end -0.67945 -0.305054)
			(stroke
				(width 0.1)
				(type default)
			)
			(layer "F.Fab")
		)
		(fp_line
			(start -0.12065 -0.305054)
			(end -0.12065 -0.2794)
			(stroke
				(width 0.1)
				(type default)
			)
			(layer "F.Fab")
		)
		(fp_line
			(start -0.12065 -0.2794)
			(end 0.12065 -0.2794)
			(stroke
				(width 0.1)
				(type default)
			)
			(layer "F.Fab")
		)
		(fp_line
			(start -0.12065 0.2794)
			(end -0.12065 0.3048)
			(stroke
				(width 0.1)
				(type default)
			)
			(layer "F.Fab")
		)
		(fp_line
			(start -0.12065 0.3048)
			(end -0.67945 0.3048)
			(stroke
				(width 0.1)
				(type default)
			)
			(layer "F.Fab")
		)
		(fp_line
			(start 0.120396 0.2794)
			(end -0.12065 0.2794)
			(stroke
				(width 0.1)
				(type default)
			)
			(layer "F.Fab")
		)
		(fp_line
			(start 0.120396 0.3048)
			(end 0.120396 0.2794)
			(stroke
				(width 0.1)
				(type default)
			)
			(layer "F.Fab")
		)
		(fp_line
			(start 0.12065 -0.3048)
			(end 0.67945 -0.3048)
			(stroke
				(width 0.1)
				(type default)
			)
			(layer "F.Fab")
		)
		(fp_line
			(start 0.12065 -0.2794)
			(end 0.12065 -0.3048)
			(stroke
				(width 0.1)
				(type default)
			)
			(layer "F.Fab")
		)
		(fp_line
			(start 0.67945 -0.3048)
			(end 0.67945 0.3048)
			(stroke
				(width 0.1)
				(type default)
			)
			(layer "F.Fab")
		)
		(fp_line
			(start 0.67945 0.3048)
			(end 0.120396 0.3048)
			(stroke
				(width 0.1)
				(type default)
			)
			(layer "F.Fab")
		)
		(pad "1" smd circle
			(at -0.40005 0)
			(size 0 0)
			(layers "F.Cu" "F.Mask" "F.Paste")
			(net "RST_SMB_SSD14_ISO_N")
		)
		(pad "2" smd circle
			(at 0.40005 0)
			(size 0 0)
			(layers "F.Cu" "F.Mask" "F.Paste")
			(net "P3V3_SSD14")
		)
	)
	(footprint ""
		(layer "F.Cu")
		(at 325.827644 -350.098614 90)
		(property "Reference" "C538"
			(at 0 0 90)
			(layer "F.SilkS")
			(hide yes)
			(effects
				(font
					(size 1.27 1.27)
				)
			)
		)
		(property "Value" ""
			(at 0 0 90)
			(layer "F.Fab")
			(effects
				(font
					(size 1.27 1.27)
				)
			)
		)
		(duplicate_pad_numbers_are_jumpers no)
		(fp_line
			(start 0.299974 -0.150114)
			(end 0.299974 0.150114)
			(stroke
				(width 0.1)
				(type default)
			)
			(layer "F.Fab")
		)
		(fp_line
			(start -0.299974 -0.150114)
			(end 0.299974 -0.150114)
			(stroke
				(width 0.1)
				(type default)
			)
			(layer "F.Fab")
		)
		(fp_line
			(start 0.299974 0.150114)
			(end -0.299974 0.150114)
			(stroke
				(width 0.1)
				(type default)
			)
			(layer "F.Fab")
		)
		(fp_line
			(start -0.299974 0.150114)
			(end -0.299974 -0.150114)
			(stroke
				(width 0.1)
				(type default)
			)
			(layer "F.Fab")
		)
		(pad "1" smd rect
			(at -0.2667 0 90)
			(size 0.3048 0.381)
			(layers "F.Cu" "F.Mask" "F.Paste")
			(net "P5E_PEX2_STN5_TX_DN<86>")
		)
		(pad "2" smd rect
			(at 0.2667 0 90)
			(size 0.3048 0.381)
			(layers "F.Cu" "F.Mask" "F.Paste")
			(net "P5E_PEX2_STN5_TX_C_DN<86>")
		)
	)
	(footprint ""
		(layer "F.Cu")
		(at 105.581958 -79.822294 90)
		(property "Reference" "R1136"
			(at 0 0 90)
			(layer "F.SilkS")
			(hide yes)
			(effects
				(font
					(size 1.27 1.27)
				)
			)
		)
		(property "Value" ""
			(at 0 0 90)
			(layer "F.Fab")
			(effects
				(font
					(size 1.27 1.27)
				)
			)
		)
		(duplicate_pad_numbers_are_jumpers no)
		(fp_line
			(start -0.7874 -0.4064)
			(end 0.7874 -0.4064)
			(stroke
				(width 0.1524)
				(type default)
			)
			(layer "F.SilkS")
		)
		(fp_line
			(start -0.12065 -0.305054)
			(end -0.12065 -0.2794)
			(stroke
				(width 0.1)
				(type default)
			)
			(layer "F.Fab")
		)
		(fp_line
			(start -0.67945 -0.305054)
			(end -0.12065 -0.305054)
			(stroke
				(width 0.1)
				(type default)
			)
			(layer "F.Fab")
		)
		(fp_line
			(start 0.67945 -0.3048)
			(end 0.67945 0.3048)
			(stroke
				(width 0.1)
				(type default)
			)
			(layer "F.Fab")
		)
		(fp_line
			(start 0.12065 -0.3048)
			(end 0.67945 -0.3048)
			(stroke
				(width 0.1)
				(type default)
			)
			(layer "F.Fab")
		)
		(fp_line
			(start 0.12065 -0.2794)
			(end 0.12065 -0.3048)
			(stroke
				(width 0.1)
				(type default)
			)
			(layer "F.Fab")
		)
		(fp_line
			(start -0.12065 -0.2794)
			(end 0.12065 -0.2794)
			(stroke
				(width 0.1)
				(type default)
			)
			(layer "F.Fab")
		)
		(fp_line
			(start 0.120396 0.2794)
			(end -0.12065 0.2794)
			(stroke
				(width 0.1)
				(type default)
			)
			(layer "F.Fab")
		)
		(fp_line
			(start -0.12065 0.2794)
			(end -0.12065 0.3048)
			(stroke
				(width 0.1)
				(type default)
			)
			(layer "F.Fab")
		)
		(fp_line
			(start 0.67945 0.3048)
			(end 0.120396 0.3048)
			(stroke
				(width 0.1)
				(type default)
			)
			(layer "F.Fab")
		)
		(fp_line
			(start 0.120396 0.3048)
			(end 0.120396 0.2794)
			(stroke
				(width 0.1)
				(type default)
			)
			(layer "F.Fab")
		)
		(fp_line
			(start -0.12065 0.3048)
			(end -0.67945 0.3048)
			(stroke
				(width 0.1)
				(type default)
			)
			(layer "F.Fab")
		)
		(fp_line
			(start -0.67945 0.3048)
			(end -0.67945 -0.305054)
			(stroke
				(width 0.1)
				(type default)
			)
			(layer "F.Fab")
		)
		(pad "1" smd circle
			(at -0.40005 0 90)
			(size 0 0)
			(layers "F.Cu" "F.Mask" "F.Paste")
			(net "CLK_100M_DB800ZL_SSD0_R_DP")
		)
		(pad "2" smd circle
			(at 0.40005 0 90)
			(size 0 0)
			(layers "F.Cu" "F.Mask" "F.Paste")
			(net "CLK_100M_DB800ZL_SSD0_DP")
		)
	)
	(footprint ""
		(layer "F.Cu")
		(at 418.092382 -28.225242 180)
		(property "Reference" "C721"
			(at 0 0 180)
			(layer "F.SilkS")
			(hide yes)
			(effects
				(font
					(size 1.27 1.27)
				)
			)
		)
		(property "Value" ""
			(at 0 0 180)
			(layer "F.Fab")
			(effects
				(font
					(size 1.27 1.27)
				)
			)
		)
		(duplicate_pad_numbers_are_jumpers no)
		(fp_line
			(start 0.299974 0.150114)
			(end -0.299974 0.150114)
			(stroke
				(width 0.1)
				(type default)
			)
			(layer "F.Fab")
		)
		(fp_line
			(start 0.299974 -0.150114)
			(end 0.299974 0.150114)
			(stroke
				(width 0.1)
				(type default)
			)
			(layer "F.Fab")
		)
		(fp_line
			(start -0.299974 0.150114)
			(end -0.299974 -0.150114)
			(stroke
				(width 0.1)
				(type default)
			)
			(layer "F.Fab")
		)
		(fp_line
			(start -0.299974 -0.150114)
			(end 0.299974 -0.150114)
			(stroke
				(width 0.1)
				(type default)
			)
			(layer "F.Fab")
		)
		(pad "1" smd rect
			(at -0.2667 0 180)
			(size 0.3048 0.381)
			(layers "F.Cu" "F.Mask" "F.Paste")
			(net "P5E_PEX3_STN2_TX_DN<36>")
		)
		(pad "2" smd rect
			(at 0.2667 0 180)
			(size 0.3048 0.381)
			(layers "F.Cu" "F.Mask" "F.Paste")
			(net "P5E_PEX3_STN2_TX_C_DN<36>")
		)
	)
	(footprint ""
		(layer "F.Cu")
		(at 225.09988 -254.18542 -90)
		(property "Reference" "C4296"
			(at 0 0 270)
			(layer "F.SilkS")
			(hide yes)
			(effects
				(font
					(size 1.27 1.27)
				)
			)
		)
		(property "Value" ""
			(at 0 0 270)
			(layer "F.Fab")
			(effects
				(font
					(size 1.27 1.27)
				)
			)
		)
		(duplicate_pad_numbers_are_jumpers no)
		(fp_line
			(start -1.2954 0.5842)
			(end -1.2954 -0.5842)
			(stroke
				(width 0.1524)
				(type default)
			)
			(layer "F.SilkS")
		)
		(fp_line
			(start 1.2954 0.5842)
			(end -1.2954 0.5842)
			(stroke
				(width 0.1524)
				(type default)
			)
			(layer "F.SilkS")
		)
		(fp_line
			(start -1.2954 -0.5842)
			(end 1.2954 -0.5842)
			(stroke
				(width 0.1524)
				(type default)
			)
			(layer "F.SilkS")
		)
		(fp_line
			(start 1.2954 -0.5842)
			(end 1.2954 0.5842)
			(stroke
				(width 0.1524)
				(type default)
			)
			(layer "F.SilkS")
		)
		(fp_line
			(start -0.8636 0.4572)
			(end -0.8636 0.4064)
			(stroke
				(width 0.1)
				(type default)
			)
			(layer "F.Fab")
		)
		(fp_line
			(start 0.8636 0.4572)
			(end -0.8636 0.4572)
			(stroke
				(width 0.1)
				(type default)
			)
			(layer "F.Fab")
		)
		(fp_line
			(start -1.1938 0.4064)
			(end -1.1938 -0.4064)
			(stroke
				(width 0.1)
				(type default)
			)
			(layer "F.Fab")
		)
		(fp_line
			(start -0.8636 0.4064)
			(end -1.1938 0.4064)
			(stroke
				(width 0.1)
				(type default)
			)
			(layer "F.Fab")
		)
		(fp_line
			(start 0.8636 0.4064)
			(end 0.8636 0.4572)
			(stroke
				(width 0.1)
				(type default)
			)
			(layer "F.Fab")
		)
		(fp_line
			(start 1.1938 0.4064)
			(end 0.8636 0.4064)
			(stroke
				(width 0.1)
				(type default)
			)
			(layer "F.Fab")
		)
		(fp_line
			(start -1.1938 -0.4064)
			(end -0.8636 -0.4064)
			(stroke
				(width 0.1)
				(type default)
			)
			(layer "F.Fab")
		)
		(fp_line
			(start -0.8636 -0.4064)
			(end -0.8636 -0.4572)
			(stroke
				(width 0.1)
				(type default)
			)
			(layer "F.Fab")
		)
		(fp_line
			(start 0.8636 -0.4064)
			(end 1.1938 -0.4064)
			(stroke
				(width 0.1)
				(type default)
			)
			(layer "F.Fab")
		)
		(fp_line
			(start 1.1938 -0.4064)
			(end 1.1938 0.4064)
			(stroke
				(width 0.1)
				(type default)
			)
			(layer "F.Fab")
		)
		(fp_line
			(start -0.8636 -0.4572)
			(end 0.8636 -0.4572)
			(stroke
				(width 0.1)
				(type default)
			)
			(layer "F.Fab")
		)
		(fp_line
			(start 0.8636 -0.4572)
			(end 0.8636 -0.4064)
			(stroke
				(width 0.1)
				(type default)
			)
			(layer "F.Fab")
		)
		(pad "1" smd rect
			(at -0.7366 0 180)
			(size 0.7112 0.8128)
			(layers "F.Cu" "F.Mask" "F.Paste")
			(net "P1V25_SERDES_VDDPLL_PEX1_C6")
		)
		(pad "2" smd rect
			(at 0.7366 0 180)
			(size 0.7112 0.8128)
			(layers "F.Cu" "F.Mask" "F.Paste")
			(net "GND")
		)
	)
	(footprint ""
		(layer "F.Cu")
		(at 290.548822 -356.244906 90)
		(property "Reference" "C592"
			(at 0 0 90)
			(layer "F.SilkS")
			(hide yes)
			(effects
				(font
					(size 1.27 1.27)
				)
			)
		)
		(property "Value" ""
			(at 0 0 90)
			(layer "F.Fab")
			(effects
				(font
					(size 1.27 1.27)
				)
			)
		)
		(duplicate_pad_numbers_are_jumpers no)
		(fp_line
			(start 0.299974 -0.150114)
			(end 0.299974 0.150114)
			(stroke
				(width 0.1)
				(type default)
			)
			(layer "F.Fab")
		)
		(fp_line
			(start -0.299974 -0.150114)
			(end 0.299974 -0.150114)
			(stroke
				(width 0.1)
				(type default)
			)
			(layer "F.Fab")
		)
		(fp_line
			(start 0.299974 0.150114)
			(end -0.299974 0.150114)
			(stroke
				(width 0.1)
				(type default)
			)
			(layer "F.Fab")
		)
		(fp_line
			(start -0.299974 0.150114)
			(end -0.299974 -0.150114)
			(stroke
				(width 0.1)
				(type default)
			)
			(layer "F.Fab")
		)
		(pad "1" smd rect
			(at -0.2667 0 90)
			(size 0.3048 0.381)
			(layers "F.Cu" "F.Mask" "F.Paste")
			(net "P5E_PEX2_STN7_TX_DN<123>")
		)
		(pad "2" smd rect
			(at 0.2667 0 90)
			(size 0.3048 0.381)
			(layers "F.Cu" "F.Mask" "F.Paste")
			(net "P5E_PEX2_STN7_TX_C_DN<123>")
		)
	)
	(footprint ""
		(layer "F.Cu")
		(at 396.94866 -350.098614 90)
		(property "Reference" "C753"
			(at 0 0 90)
			(layer "F.SilkS")
			(hide yes)
			(effects
				(font
					(size 1.27 1.27)
				)
			)
		)
		(property "Value" ""
			(at 0 0 90)
			(layer "F.Fab")
			(effects
				(font
					(size 1.27 1.27)
				)
			)
		)
		(duplicate_pad_numbers_are_jumpers no)
		(fp_line
			(start 0.299974 -0.150114)
			(end 0.299974 0.150114)
			(stroke
				(width 0.1)
				(type default)
			)
			(layer "F.Fab")
		)
		(fp_line
			(start -0.299974 -0.150114)
			(end 0.299974 -0.150114)
			(stroke
				(width 0.1)
				(type default)
			)
			(layer "F.Fab")
		)
		(fp_line
			(start 0.299974 0.150114)
			(end -0.299974 0.150114)
			(stroke
				(width 0.1)
				(type default)
			)
			(layer "F.Fab")
		)
		(fp_line
			(start -0.299974 0.150114)
			(end -0.299974 -0.150114)
			(stroke
				(width 0.1)
				(type default)
			)
			(layer "F.Fab")
		)
		(pad "1" smd rect
			(at -0.2667 0 90)
			(size 0.3048 0.381)
			(layers "F.Cu" "F.Mask" "F.Paste")
			(net "P5E_PEX3_STN5_TX_DN<84>")
		)
		(pad "2" smd rect
			(at 0.2667 0 90)
			(size 0.3048 0.381)
			(layers "F.Cu" "F.Mask" "F.Paste")
			(net "P5E_PEX3_STN5_TX_C_DN<84>")
		)
	)
)
